(kicad_pcb
	(version 20241229)
	(generator "pcbnew")
	(generator_version "9.0")
	(general
		(thickness 1.6642)
		(legacy_teardrops no)
	)
	(paper "A3")
	(title_block
		(title "PolarFire SoM")
		(date "2025-07-22")
		(rev "1.1.4")
		(company "Antmicro Ltd")
		(comment 1 "www.antmicro.com")
		(comment 9 "footprint 85 of 470 (U1), pads 135-205 of 484")
	)
	(layers
		(0 "F.Cu" mixed)
		(4 "In1.Cu" power)
		(6 "In2.Cu" signal)
		(8 "In3.Cu" power)
		(10 "In4.Cu" signal)
		(12 "In5.Cu" power)
		(14 "In6.Cu" power)
		(16 "In7.Cu" signal)
		(18 "In8.Cu" power)
		(20 "In9.Cu" signal)
		(22 "In10.Cu" power)
		(24 "In11.Cu" signal)
		(26 "In12.Cu" signal)
		(2 "B.Cu" mixed)
		(9 "F.Adhes" user "F.Adhesive")
		(11 "B.Adhes" user "B.Adhesive")
		(13 "F.Paste" user)
		(15 "B.Paste" user)
		(5 "F.SilkS" user "F.Silkscreen")
		(7 "B.SilkS" user "B.Silkscreen")
		(1 "F.Mask" user)
		(3 "B.Mask" user)
		(17 "Dwgs.User" user "User.Drawings")
		(19 "Cmts.User" user "User.Comments")
		(21 "Eco1.User" user "User.Eco1")
		(23 "Eco2.User" user "User.Eco2")
		(25 "Edge.Cuts" user)
		(27 "Margin" user)
		(31 "F.CrtYd" user "F.Courtyard")
		(29 "B.CrtYd" user "B.Courtyard")
		(35 "F.Fab" user)
		(33 "B.Fab" user)
	)
	(footprint "antmicro-footprints:BGA-484_19x19mm_Layout22x22_P0.8mm_FCVG484"
		(layer "F.Cu")
		(at 197.699 132.701 -90)
		(descr "FCVG484, 19.0x19.0mm, 484 Ball, 22x22 Layout, 0.8mm Pitch")
		(tags "BGA 484 0.8")
		(property "Reference" "U1"
			(at 0 -10.8 270)
			(layer "F.SilkS")
			(effects
				(font
					(size 0.7 0.7)
					(thickness 0.15)
				)
				(justify left bottom)
			)
		)
		(property "Value" "MPFS250T-FCVG484"
			(at 0 11.5 270)
			(layer "F.Fab")
			(hide yes)
			(effects
				(font
					(size 0.7 0.7)
					(thickness 0.15)
				)
				(justify left bottom)
			)
		)
		(property "Datasheet" "https://ww1.microchip.com/downloads/aemDocuments/documents/FPGA/ProductDocuments/DataSheets/PolarFire-SoC-Datasheet-DS00004248.pdf"
			(at 0 0 270)
			(layer "F.Fab")
			(hide yes)
			(effects
				(font
					(size 1.27 1.27)
					(thickness 0.15)
				)
			)
		)
		(property "Description" "RISC-V System On Chip (SOC) IC PolarFire® FPGA - 254K Logic Modules 484-FCBGA (19x19)"
			(at 0 0 270)
			(layer "F.Fab")
			(hide yes)
			(effects
				(font
					(size 1.27 1.27)
					(thickness 0.15)
				)
			)
		)
		(property "MPN" "MPFS250T-FCVG484E"
			(at 0 0 270)
			(unlocked yes)
			(layer "F.Fab")
			(hide yes)
			(effects
				(font
					(size 1 1)
					(thickness 0.15)
				)
			)
		)
		(property "Manufacturer" "Microchip Technology"
			(at 0 0 270)
			(unlocked yes)
			(layer "F.Fab")
			(hide yes)
			(effects
				(font
					(size 1 1)
					(thickness 0.15)
				)
			)
		)
		(property "VSD_class" "MPFS250T"
			(at 0 0 270)
			(unlocked yes)
			(layer "F.Fab")
			(hide yes)
			(effects
				(font
					(size 1 1)
					(thickness 0.15)
				)
			)
		)
		(property "Author" "Antmicro"
			(at 0 0 270)
			(unlocked yes)
			(layer "F.Fab")
			(hide yes)
			(effects
				(font
					(size 1 1)
					(thickness 0.15)
				)
			)
		)
		(property "License" "Apache-2.0"
			(at 0 0 270)
			(unlocked yes)
			(layer "F.Fab")
			(hide yes)
			(effects
				(font
					(size 1 1)
					(thickness 0.15)
				)
			)
		)
		(sheetname "/FPGA Config/")
		(sheetfile "fpga-config.kicad_sch")
		(attr smd)
		(pad "E3" smd circle
			(at -6.8 -5.201 270)
			(size 0.45 0.45)
			(layers "F.Cu" "F.Mask" "F.Paste")
			(net 295 "Net-(U1C-MSSIO36B2)")
			(pinfunction "MSSIO36B2")
			(pintype "bidirectional")
			(die_length 8.49579)
		)
		(pad "E4" smd circle
			(at -6 -5.201 270)
			(size 0.45 0.45)
			(layers "F.Cu" "F.Mask" "F.Paste")
			(net 384 "unconnected-(U1C-MSSIO31B2-PadE4)")
			(pinfunction "MSSIO31B2")
			(pintype "bidirectional+no_connect")
			(die_length 10.1708)
		)
		(pad "E5" smd circle
			(at -5.201 -5.201 270)
			(size 0.45 0.45)
			(layers "F.Cu" "F.Mask" "F.Paste")
			(net 428 "PAC1934_SLOW")
			(pinfunction "MSSIO30B2")
			(pintype "bidirectional")
			(die_length 11.7656)
		)
		(pad "E6" smd circle
			(at -4.401 -5.201 270)
			(size 0.45 0.45)
			(layers "F.Cu" "F.Mask" "F.Paste")
			(net 286 "/FPGA Config/Flash.CLK")
			(pinfunction "SCK")
			(pintype "bidirectional")
			(die_length 5.66068)
		)
		(pad "E7" smd circle
			(at -3.601 -5.201 270)
			(size 0.45 0.45)
			(layers "F.Cu" "F.Mask" "F.Paste")
			(net 50 "+3V3")
			(pinfunction "VDDI3")
			(pintype "power_in")
		)
		(pad "E8" smd circle
			(at -2.8 -5.201 270)
			(size 0.45 0.45)
			(layers "F.Cu" "F.Mask" "F.Paste")
			(net 189 "Net-(U1D-TDO)")
			(pinfunction "TDO")
			(pintype "output")
			(die_length 4.21041)
		)
		(pad "E9" smd circle
			(at -2 -5.201 270)
			(size 0.45 0.45)
			(layers "F.Cu" "F.Mask" "F.Paste")
			(net 124 "JTAG_TCK")
			(pinfunction "TCK")
			(pintype "input")
			(die_length 4.35251)
		)
		(pad "E10" smd circle
			(at -1.2 -5.201 270)
			(size 0.45 0.45)
			(layers "F.Cu" "F.Mask" "F.Paste")
			(net 545 "/FPGA GPIO/Crosslink.CLK")
			(pinfunction "GPIO180PB1")
			(pintype "bidirectional")
			(die_length 11.3535)
		)
		(pad "E11" smd circle
			(at -0.401 -5.201 270)
			(size 0.45 0.45)
			(layers "F.Cu" "F.Mask" "F.Paste")
			(net 341 "/FPGA GPIO/USER_LED_G")
			(pinfunction "GPIO183NB1")
			(pintype "bidirectional")
			(die_length 11.0538)
		)
		(pad "E12" smd circle
			(at 0.4 -5.201 270)
			(size 0.45 0.45)
			(layers "F.Cu" "F.Mask" "F.Paste")
			(net 417 "GND")
			(pinfunction "VSS")
			(pintype "passive")
		)
		(pad "E13" smd circle
			(at 1.199 -5.201 270)
			(size 0.45 0.45)
			(layers "F.Cu" "F.Mask" "F.Paste")
			(net 224 "/FPGA GPIO/USER_LED_B")
			(pinfunction "GPIO184PB1")
			(pintype "bidirectional")
			(die_length 12.5139)
		)
		(pad "E14" smd circle
			(at 1.999 -5.201 270)
			(size 0.45 0.45)
			(layers "F.Cu" "F.Mask" "F.Paste")
			(net 21 "GPIO25")
			(pinfunction "GPIO9NB1")
			(pintype "bidirectional")
			(die_length 10.4171)
		)
		(pad "E15" smd circle
			(at 2.799 -5.201 270)
			(size 0.45 0.45)
			(layers "F.Cu" "F.Mask" "F.Paste")
			(net 386 "unconnected-(U1B-GPIO9PB1{slash}CLKIN_S_8{slash}CCC_SE_CLKIN_S_8{slash}CCC_SE_PLL0_OUT0-PadE15)")
			(pinfunction "GPIO9PB1/CLKIN_S_8/CCC_SE_CLKIN_S_8/CCC_SE_PLL0_OUT0")
			(pintype "bidirectional+no_connect")
			(die_length 10.4372)
		)
		(pad "E16" smd circle
			(at 3.6 -5.201 270)
			(size 0.45 0.45)
			(layers "F.Cu" "F.Mask" "F.Paste")
			(net 289 "~{Crosslink_RESET}")
			(pinfunction "GPIO10PB1/CCC_SE_PLL0_OUT1")
			(pintype "bidirectional")
			(die_length 10.5384)
		)
		(pad "E17" smd circle
			(at 4.4 -5.201 270)
			(size 0.45 0.45)
			(layers "F.Cu" "F.Mask" "F.Paste")
			(net 649 "VDD")
			(pinfunction "VDDI1")
			(pintype "passive")
		)
		(pad "E18" smd circle
			(at 5.2 -5.201 270)
			(size 0.45 0.45)
			(layers "F.Cu" "F.Mask" "F.Paste")
			(net 23 "GPIO24")
			(pinfunction "GPIO16NB1")
			(pintype "bidirectional")
			(die_length 10.4012)
		)
		(pad "E19" smd circle
			(at 5.999 -5.201 270)
			(size 0.45 0.45)
			(layers "F.Cu" "F.Mask" "F.Paste")
			(net 22 "GPIO10")
			(pinfunction "GPIO14PB1/DQS/CCC_SE_PLL1_OUT0")
			(pintype "bidirectional")
			(die_length 10.7473)
		)
		(pad "E20" smd circle
			(at 6.799 -5.201 270)
			(size 0.45 0.45)
			(layers "F.Cu" "F.Mask" "F.Paste")
			(net 417 "GND")
			(pinfunction "VSS")
			(pintype "passive")
		)
		(pad "E21" smd circle
			(at 7.599 -5.201 270)
			(size 0.45 0.45)
			(layers "F.Cu" "F.Mask" "F.Paste")
			(net 417 "GND")
			(pinfunction "VSS")
			(pintype "passive")
		)
		(pad "E22" smd circle
			(at 8.4 -5.201 270)
			(size 0.45 0.45)
			(layers "F.Cu" "F.Mask" "F.Paste")
			(net 417 "GND")
			(pinfunction "VSS")
			(pintype "passive")
		)
		(pad "F1" smd circle
			(at -8.401 -4.401 270)
			(size 0.45 0.45)
			(layers "F.Cu" "F.Mask" "F.Paste")
			(net 640 "/FPGA GPIO/ULPI.DIR")
			(pinfunction "MSSIO15B2")
			(pintype "bidirectional")
			(die_length 9.16566)
		)
		(pad "F2" smd circle
			(at -7.6 -4.401 270)
			(size 0.45 0.45)
			(layers "F.Cu" "F.Mask" "F.Paste")
			(net 641 "/FPGA GPIO/ULPI.DATA0")
			(pinfunction "MSSIO18B2")
			(pintype "bidirectional")
			(die_length 8.71051)
		)
		(pad "F3" smd circle
			(at -6.8 -4.401 270)
			(size 0.45 0.45)
			(layers "F.Cu" "F.Mask" "F.Paste")
			(net 642 "/FPGA GPIO/ULPI.DATA7")
			(pinfunction "MSSIO25B2")
			(pintype "bidirectional")
			(die_length 8.44991)
		)
		(pad "F4" smd circle
			(at -6 -4.401 270)
			(size 0.45 0.45)
			(layers "F.Cu" "F.Mask" "F.Paste")
			(net 649 "VDD")
			(pinfunction "VDDI2")
			(pintype "passive")
		)
		(pad "F5" smd circle
			(at -5.201 -4.401 270)
			(size 0.45 0.45)
			(layers "F.Cu" "F.Mask" "F.Paste")
			(net 643 "/FPGA GPIO/ULPI.DATA3")
			(pinfunction "MSSIO21B2")
			(pintype "bidirectional")
			(die_length 11.2446)
		)
		(pad "F6" smd circle
			(at -4.401 -4.401 270)
			(size 0.45 0.45)
			(layers "F.Cu" "F.Mask" "F.Paste")
			(net 644 "/FPGA GPIO/ULPI.DATA6")
			(pinfunction "MSSIO24B2")
			(pintype "bidirectional")
			(die_length 11.3029)
		)
		(pad "F7" smd circle
			(at -3.601 -4.401 270)
			(size 0.45 0.45)
			(layers "F.Cu" "F.Mask" "F.Paste")
			(net 287 "/FPGA Config/Flash.MOSI")
			(pinfunction "SDO")
			(pintype "output")
			(die_length 5.03293)
		)
		(pad "F8" smd circle
			(at -2.8 -4.401 270)
			(size 0.45 0.45)
			(layers "F.Cu" "F.Mask" "F.Paste")
			(net 123 "JTAG_TMS")
			(pinfunction "TMS")
			(pintype "input")
			(die_length 4.98175)
		)
		(pad "F9" smd circle
			(at -2 -4.401 270)
			(size 0.45 0.45)
			(layers "F.Cu" "F.Mask" "F.Paste")
			(net 417 "GND")
			(pinfunction "VSS")
			(pintype "passive")
		)
		(pad "F10" smd circle
			(at -1.2 -4.401 270)
			(size 0.45 0.45)
			(layers "F.Cu" "F.Mask" "F.Paste")
			(net 563 "/FPGA GPIO/Crosslink.MISO")
			(pinfunction "GPIO180NB1")
			(pintype "bidirectional")
			(die_length 11.3496)
		)
		(pad "F11" smd circle
			(at -0.401 -4.401 270)
			(size 0.45 0.45)
			(layers "F.Cu" "F.Mask" "F.Paste")
			(net 63 "SDA6{slash}RPI_GPIO22")
			(pinfunction "GPIO181NB1")
			(pintype "bidirectional")
			(die_length 11.0237)
		)
		(pad "F12" smd circle
			(at 0.4 -4.401 270)
			(size 0.45 0.45)
			(layers "F.Cu" "F.Mask" "F.Paste")
			(net 564 "/FPGA GPIO/Crosslink.SCL")
			(pinfunction "GPIO181PB1")
			(pintype "bidirectional")
			(die_length 11.0311)
		)
		(pad "F13" smd circle
			(at 1.199 -4.401 270)
			(size 0.45 0.45)
			(layers "F.Cu" "F.Mask" "F.Paste")
			(net 219 "unconnected-(U1B-GPIO184NB1-PadF13)")
			(pinfunction "GPIO184NB1")
			(pintype "bidirectional+no_connect")
			(die_length 12.4935)
		)
		(pad "F14" smd circle
			(at 1.999 -4.401 270)
			(size 0.45 0.45)
			(layers "F.Cu" "F.Mask" "F.Paste")
			(net 649 "VDD")
			(pinfunction "VDDI1")
			(pintype "passive")
		)
		(pad "F15" smd circle
			(at 2.799 -4.401 270)
			(size 0.45 0.45)
			(layers "F.Cu" "F.Mask" "F.Paste")
			(net 565 "/FPGA GPIO/PF_ETH_PWDN_n")
			(pinfunction "GPIO6PB1")
			(pintype "bidirectional")
			(die_length 10.3454)
		)
		(pad "F16" smd circle
			(at 3.6 -4.401 270)
			(size 0.45 0.45)
			(layers "F.Cu" "F.Mask" "F.Paste")
			(net 132 "SCL6{slash}RPI_GPIO23")
			(pinfunction "GPIO11NB1")
			(pintype "bidirectional")
			(die_length 10.7073)
		)
		(pad "F17" smd circle
			(at 4.4 -4.401 270)
			(size 0.45 0.45)
			(layers "F.Cu" "F.Mask" "F.Paste")
			(net 392 "unconnected-(U1B-GPIO11PB1{slash}CLKIN_S_9{slash}CCC_SE_CLKIN_S_9-PadF17)")
			(pinfunction "GPIO11PB1/CLKIN_S_9/CCC_SE_CLKIN_S_9")
			(pintype "bidirectional+no_connect")
			(die_length 10.7212)
		)
		(pad "F18" smd circle
			(at 5.2 -4.401 270)
			(size 0.45 0.45)
			(layers "F.Cu" "F.Mask" "F.Paste")
			(net 417 "GND")
			(pinfunction "VSS")
			(pintype "passive")
		)
		(pad "F19" smd circle
			(at 5.999 -4.401 270)
			(size 0.45 0.45)
			(layers "F.Cu" "F.Mask" "F.Paste")
			(net 417 "GND")
			(pinfunction "VSS")
			(pintype "passive")
		)
		(pad "F20" smd circle
			(at 6.799 -4.401 270)
			(size 0.45 0.45)
			(layers "F.Cu" "F.Mask" "F.Paste")
			(net 417 "GND")
			(pinfunction "VSS")
			(pintype "passive")
		)
		(pad "F21" smd circle
			(at 7.599 -4.401 270)
			(size 0.45 0.45)
			(layers "F.Cu" "F.Mask" "F.Paste")
			(net 53 "/PCIe/XCVR_TX0_N")
			(pinfunction "XCVR_0_TX0_N")
			(pintype "output")
			(die_length 8.36558)
		)
		(pad "F22" smd circle
			(at 8.4 -4.401 270)
			(size 0.45 0.45)
			(layers "F.Cu" "F.Mask" "F.Paste")
			(net 64 "/PCIe/XCVR_TX0_P")
			(pinfunction "XCVR_0_TX0_P")
			(pintype "output")
			(die_length 8.34976)
		)
		(pad "G1" smd circle
			(at -8.401 -3.601 270)
			(size 0.45 0.45)
			(layers "F.Cu" "F.Mask" "F.Paste")
			(net 649 "VDD")
			(pinfunction "VDDI2")
			(pintype "passive")
		)
		(pad "G2" smd circle
			(at -7.6 -3.601 270)
			(size 0.45 0.45)
			(layers "F.Cu" "F.Mask" "F.Paste")
			(net 636 "/FPGA GPIO/ULPI.CLK")
			(pinfunction "MSSIO14B2")
			(pintype "bidirectional")
			(die_length 8.06194)
		)
		(pad "G3" smd circle
			(at -6.8 -3.601 270)
			(size 0.45 0.45)
			(layers "F.Cu" "F.Mask" "F.Paste")
			(net 645 "/FPGA GPIO/ULPI.DATA2")
			(pinfunction "MSSIO20B2")
			(pintype "bidirectional")
			(die_length 7.76964)
		)
		(pad "G4" smd circle
			(at -6 -3.601 270)
			(size 0.45 0.45)
			(layers "F.Cu" "F.Mask" "F.Paste")
			(net 646 "/FPGA GPIO/ULPI.STP")
			(pinfunction "MSSIO17B2")
			(pintype "bidirectional")
			(die_length 9.16295)
		)
		(pad "G5" smd circle
			(at -5.201 -3.601 270)
			(size 0.45 0.45)
			(layers "F.Cu" "F.Mask" "F.Paste")
			(net 647 "/FPGA GPIO/ULPI.NXT")
			(pinfunction "MSSIO16B2")
			(pintype "bidirectional")
			(die_length 10.71)
		)
		(pad "G6" smd circle
			(at -4.401 -3.601 270)
			(size 0.45 0.45)
			(layers "F.Cu" "F.Mask" "F.Paste")
			(net 417 "GND")
			(pinfunction "VSS")
			(pintype "passive")
		)
		(pad "G7" smd circle
			(at -3.601 -3.601 270)
			(size 0.45 0.45)
			(layers "F.Cu" "F.Mask" "F.Paste")
			(net 288 "/FPGA Config/Flash.CS")
			(pinfunction "SS")
			(pintype "bidirectional")
			(die_length 5.17538)
		)
		(pad "G8" smd circle
			(at -2.8 -3.601 270)
			(size 0.45 0.45)
			(layers "F.Cu" "F.Mask" "F.Paste")
			(net 127 "JTAG_RESET_n")
			(pinfunction "TRSTB")
			(pintype "input")
			(die_length 4.93266)
		)
		(pad "G9" smd circle
			(at -2 -3.601 270)
			(size 0.45 0.45)
			(layers "F.Cu" "F.Mask" "F.Paste")
			(net 126 "JTAG_TDI")
			(pinfunction "TDI")
			(pintype "input")
			(die_length 5.59612)
		)
		(pad "G10" smd circle
			(at -1.2 -3.601 270)
			(size 0.45 0.45)
			(layers "F.Cu" "F.Mask" "F.Paste")
			(net 254 "Net-(U1D-FF_EXIT_N)")
			(pinfunction "FF_EXIT_N")
			(pintype "input")
			(die_length 6.55259)
		)
		(pad "G11" smd circle
			(at -0.401 -3.601 270)
			(size 0.45 0.45)
			(layers "F.Cu" "F.Mask" "F.Paste")
			(net 649 "VDD")
			(pinfunction "VDDI1")
			(pintype "passive")
		)
		(pad "G12" smd circle
			(at 0.4 -3.601 270)
			(size 0.45 0.45)
			(layers "F.Cu" "F.Mask" "F.Paste")
			(net 32 "UART4_RX{slash}RPI_GPIO09")
			(pinfunction "GPIO182NB1/DQS")
			(pintype "bidirectional")
			(die_length 12.3908)
		)
		(pad "G13" smd circle
			(at 1.199 -3.601 270)
			(size 0.45 0.45)
			(layers "F.Cu" "F.Mask" "F.Paste")
			(net 396 "unconnected-(U1B-GPIO185PB1-PadG13)")
			(pinfunction "GPIO185PB1")
			(pintype "bidirectional+no_connect")
			(die_length 12.308)
		)
		(pad "G14" smd circle
			(at 1.999 -3.601 270)
			(size 0.45 0.45)
			(layers "F.Cu" "F.Mask" "F.Paste")
			(net 566 "/FPGA GPIO/PF_ETH_RESET_n")
			(pinfunction "GPIO6NB1")
			(pintype "bidirectional")
			(die_length 10.3354)
		)
		(pad "G15" smd circle
			(at 2.799 -3.601 270)
			(size 0.45 0.45)
			(layers "F.Cu" "F.Mask" "F.Paste")
			(net 133 "SPI6_CEO_N{slash}RPI_GPIO18")
			(pinfunction "GPIO7PB1")
			(pintype "bidirectional")
			(die_length 10.6356)
		)
		(pad "G16" smd circle
			(at 3.6 -3.601 270)
			(size 0.45 0.45)
			(layers "F.Cu" "F.Mask" "F.Paste")
			(net 417 "GND")
			(pinfunction "VSS")
			(pintype "passive")
		)
		(pad "G17" smd circle
			(at 4.4 -3.601 270)
			(size 0.45 0.45)
			(layers "F.Cu" "F.Mask" "F.Paste")
			(net 397 "unconnected-(U1B-GPIO8PB1{slash}DQS{slash}CCC_SE_PLL0_OUT0-PadG17)")
			(pinfunction "GPIO8PB1/DQS/CCC_SE_PLL0_OUT0")
			(pintype "bidirectional+no_connect")
			(die_length 11.6563)
		)
		(pad "G18" smd circle
			(at 5.2 -3.601 270)
			(size 0.45 0.45)
			(layers "F.Cu" "F.Mask" "F.Paste")
			(net 417 "GND")
			(pinfunction "VSS")
			(pintype "passive")
		)
		(pad "G19" smd circle
			(at 5.999 -3.601 270)
			(size 0.45 0.45)
			(layers "F.Cu" "F.Mask" "F.Paste")
			(net 105 "/Bottom Connector/PCIE.RXD0_N")
			(pinfunction "XCVR_0_RX0_N")
			(pintype "input")
			(die_length 6.56405)
		)
		(pad "G20" smd circle
			(at 6.799 -3.601 270)
			(size 0.45 0.45)
			(layers "F.Cu" "F.Mask" "F.Paste")
			(net 102 "/Bottom Connector/PCIE.RXD0_P")
			(pinfunction "XCVR_0_RX0_P")
			(pintype "input")
			(die_length 6.55062)
		)
		(pad "G21" smd circle
			(at 7.599 -3.601 270)
			(size 0.45 0.45)
			(layers "F.Cu" "F.Mask" "F.Paste")
			(net 47 "+1V05")
			(pinfunction "VDDA")
			(pintype "power_in")
		)
		(pad "G22" smd circle
			(at 8.4 -3.601 270)
			(size 0.45 0.45)
			(layers "F.Cu" "F.Mask" "F.Paste")
			(net 417 "GND")
			(pinfunction "VSS")
			(pintype "passive")
		)
		(pad "H1" smd circle
			(at -8.401 -2.8 270)
			(size 0.45 0.45)
			(layers "F.Cu" "F.Mask" "F.Paste")
			(net 235 "/FPGA MSSIO/MEM.DAT0")
			(pinfunction "MSSIO2B4")
			(pintype "bidirectional")
			(die_length 8.33301)
		)
		(pad "H2" smd circle
			(at -7.6 -2.8 270)
			(size 0.45 0.45)
			(layers "F.Cu" "F.Mask" "F.Paste")
			(net 215 "/FPGA MSSIO/MEM.DAT7")
			(pinfunction "MSSIO11B4")
			(pintype "bidirectional")
			(die_length 7.77805)
		)
		(pad "H3" smd circle
			(at -6.8 -2.8 270)
			(size 0.45 0.45)
			(layers "F.Cu" "F.Mask" "F.Paste")
			(net 417 "GND")
			(pinfunction "VSS")
			(pintype "passive")
		)
		(pad "H4" smd circle
			(at -6 -2.8 270)
			(size 0.45 0.45)
			(layers "F.Cu" "F.Mask" "F.Paste")
			(net 387 "/FPGA MSSIO/EMMC.RST_n")
			(pinfunction "MSSIO7B4")
			(pintype "bidirectional")
			(die_length 9.16535)
		)
		(pad "H5" smd circle
			(at -5.201 -2.8 270)
			(size 0.45 0.45)
			(layers "F.Cu" "F.Mask" "F.Paste")
			(net 626 "unconnected-(U1E-MSSIO12B4-PadH5)")
			(pinfunction "MSSIO12B4")
			(pintype "bidirectional+no_connect")
			(die_length 9.27031)
		)
		(pad "H6" smd circle
			(at -4.401 -2.8 270)
			(size 0.45 0.45)
			(layers "F.Cu" "F.Mask" "F.Paste")
			(net 216 "/FPGA MSSIO/MEM.DAT5")
			(pinfunction "MSSIO9B4")
			(pintype "bidirectional")
			(die_length 10.6795)
		)
		(pad "H7" smd circle
			(at -3.601 -2.8 270)
			(size 0.45 0.45)
			(layers "F.Cu" "F.Mask" "F.Paste")
			(net 655 "/FPGA Config/DEVRST_N")
			(pinfunction "DEVRST_N")
			(pintype "input")
			(die_length 5.65884)
		)
	)
)
